# T6G (Grand Teton) — schematic netlist excerpt (pin names and nets, part order shuffled) for the footprints in the layout excerpt that follows; sources: Cadence DE-HDL packaged netlist, KiCad conversion of 04192023_DAF0TMB3IC0_F0TG_MB_C_brd_V02_OCP.brd

R4073  Q_RES  4.7K 5% CHIP  pkg 0402LF  page 146 : A = P12V_E1S_EN_0_R ; B = GND
R5018  Q_RES  1K 1% EMPTY  pkg 0402LF  page 159 : A = PVDD11_S3_P1 ; B = I3C_SCM_2_R_SCL
C722  Q_CAP_DIFFBUS  DIFF BUS_0.22UF 6.3V 20% X6S  pkg C0201  page 66 : \1\ = P5E_CPU1_P1_TX_C_DN<9> ; \2\ = P5E_CPU1_P1_TX_DN<9>

(kicad_pcb
	(version 20260206)
	(generator "pcbnew")
	(generator_version "10.0")
	(general
		(thickness 1.6)
		(legacy_teardrops no)
	)
	(paper "A4")
	(title_block
		(title "04192023_DAF0TMB3IC0_F0TG_MB_C_brd_V02_OCP.brd")
		(comment 1 "Grand Teton / footprints 2779-2781 of 8354")
	)
	(layers
		(0 "F.Cu" signal "TOP")
		(4 "In1.Cu" signal "GND")
		(6 "In2.Cu" signal "IN1")
		(8 "In3.Cu" signal "GND1")
		(10 "In4.Cu" signal "IN2")
		(12 "In5.Cu" signal "GND2")
		(14 "In6.Cu" signal "IN3")
		(16 "In7.Cu" signal "GND3")
		(18 "In8.Cu" signal "VCC")
		(20 "In9.Cu" signal "VCC1")
		(22 "In10.Cu" signal "GND4")
		(24 "In11.Cu" signal "IN4")
		(26 "In12.Cu" signal "GND5")
		(28 "In13.Cu" signal "IN5")
		(30 "In14.Cu" signal "GND6")
		(32 "In15.Cu" signal "IN6")
		(34 "In16.Cu" signal "GND7")
		(2 "B.Cu" signal "BOTTOM")
		(9 "F.Adhes" user "F.Adhesive")
		(11 "B.Adhes" user "B.Adhesive")
		(13 "F.Paste" user "Package Geometry/Pastemask Top")
		(15 "B.Paste" user "Package Geometry/Pastemask Bottom")
		(5 "F.SilkS" user "Ref Des/Silkscreen Top")
		(7 "B.SilkS" user "Ref Des/Silkscreen Bottom")
		(1 "F.Mask" user "Board Geometry/Soldermask Top")
		(3 "B.Mask" user "Board Geometry/Soldermask Bottom")
		(17 "Dwgs.User" user "User.Drawings")
		(19 "Cmts.User" user "User.Comments")
		(21 "Eco1.User" user "User.Eco1")
		(23 "Eco2.User" user "User.Eco2")
		(25 "Edge.Cuts" user "Board Geometry/Outline")
		(27 "Margin" user)
		(31 "F.CrtYd" user "Package Geometry/Place Bound Top")
		(29 "B.CrtYd" user "Package Geometry/Place Bound Bottom")
		(35 "F.Fab" user "Ref Des/Assembly Top")
		(33 "B.Fab" user "Ref Des/Assembly Bottom")
	)
	(footprint ""
		(layer "F.Cu")
		(at 91.748102 -370.57203 -90)
		(property "Reference" "C722"
			(at 0 0 270)
			(layer "F.SilkS")
			(hide yes)
			(effects
				(font
					(size 1.27 1.27)
				)
			)
		)
		(property "Value" ""
			(at 0 0 270)
			(layer "F.Fab")
			(effects
				(font
					(size 1.27 1.27)
				)
			)
		)
		(duplicate_pad_numbers_are_jumpers no)
		(fp_line
			(start -0.299974 0.150114)
			(end -0.299974 -0.150114)
			(stroke
				(width 0.1)
				(type default)
			)
			(layer "F.Fab")
		)
		(fp_line
			(start 0.299974 0.150114)
			(end -0.299974 0.150114)
			(stroke
				(width 0.1)
				(type default)
			)
			(layer "F.Fab")
		)
		(fp_line
			(start -0.299974 -0.150114)
			(end 0.299974 -0.150114)
			(stroke
				(width 0.1)
				(type default)
			)
			(layer "F.Fab")
		)
		(fp_line
			(start 0.299974 -0.150114)
			(end 0.299974 0.150114)
			(stroke
				(width 0.1)
				(type default)
			)
			(layer "F.Fab")
		)
		(pad "1" smd rect
			(at -0.2667 0 270)
			(size 0.3048 0.381)
			(layers "F.Cu" "F.Mask" "F.Paste")
			(net "P5E_CPU1_P1_TX_C_DN<9>")
		)
		(pad "2" smd rect
			(at 0.2667 0 270)
			(size 0.3048 0.381)
			(layers "F.Cu" "F.Mask" "F.Paste")
			(net "P5E_CPU1_P1_TX_DN<9>")
		)
	)
	(footprint ""
		(layer "F.Cu")
		(at 250.55957 -67.254374 180)
		(property "Reference" "R4073"
			(at 0 0 180)
			(layer "F.SilkS")
			(hide yes)
			(effects
				(font
					(size 1.27 1.27)
				)
			)
		)
		(property "Value" ""
			(at 0 0 180)
			(layer "F.Fab")
			(effects
				(font
					(size 1.27 1.27)
				)
			)
		)
		(duplicate_pad_numbers_are_jumpers no)
		(fp_line
			(start 0.7874 0.4064)
			(end -0.7874 0.4064)
			(stroke
				(width 0.1524)
				(type default)
			)
			(layer "F.SilkS")
		)
		(fp_line
			(start 0.7874 -0.4064)
			(end 0.7874 0.4064)
			(stroke
				(width 0.1524)
				(type default)
			)
			(layer "F.SilkS")
		)
		(fp_line
			(start -0.7874 0.4064)
			(end -0.7874 -0.4064)
			(stroke
				(width 0.1524)
				(type default)
			)
			(layer "F.SilkS")
		)
		(fp_line
			(start -0.7874 -0.4064)
			(end 0.7874 -0.4064)
			(stroke
				(width 0.1524)
				(type default)
			)
			(layer "F.SilkS")
		)
		(fp_line
			(start 0.67945 0.3048)
			(end 0.120396 0.3048)
			(stroke
				(width 0.1)
				(type default)
			)
			(layer "F.Fab")
		)
		(fp_line
			(start 0.67945 -0.3048)
			(end 0.67945 0.3048)
			(stroke
				(width 0.1)
				(type default)
			)
			(layer "F.Fab")
		)
		(fp_line
			(start 0.12065 -0.2794)
			(end 0.12065 -0.3048)
			(stroke
				(width 0.1)
				(type default)
			)
			(layer "F.Fab")
		)
		(fp_line
			(start 0.12065 -0.3048)
			(end 0.67945 -0.3048)
			(stroke
				(width 0.1)
				(type default)
			)
			(layer "F.Fab")
		)
		(fp_line
			(start 0.120396 0.3048)
			(end 0.120396 0.2794)
			(stroke
				(width 0.1)
				(type default)
			)
			(layer "F.Fab")
		)
		(fp_line
			(start 0.120396 0.2794)
			(end -0.12065 0.2794)
			(stroke
				(width 0.1)
				(type default)
			)
			(layer "F.Fab")
		)
		(fp_line
			(start -0.12065 0.3048)
			(end -0.67945 0.3048)
			(stroke
				(width 0.1)
				(type default)
			)
			(layer "F.Fab")
		)
		(fp_line
			(start -0.12065 0.2794)
			(end -0.12065 0.3048)
			(stroke
				(width 0.1)
				(type default)
			)
			(layer "F.Fab")
		)
		(fp_line
			(start -0.12065 -0.2794)
			(end 0.12065 -0.2794)
			(stroke
				(width 0.1)
				(type default)
			)
			(layer "F.Fab")
		)
		(fp_line
			(start -0.12065 -0.305054)
			(end -0.12065 -0.2794)
			(stroke
				(width 0.1)
				(type default)
			)
			(layer "F.Fab")
		)
		(fp_line
			(start -0.67945 0.3048)
			(end -0.67945 -0.305054)
			(stroke
				(width 0.1)
				(type default)
			)
			(layer "F.Fab")
		)
		(fp_line
			(start -0.67945 -0.305054)
			(end -0.12065 -0.305054)
			(stroke
				(width 0.1)
				(type default)
			)
			(layer "F.Fab")
		)
		(pad "1" smd circle
			(at -0.40005 0 180)
			(size 0 0)
			(layers "F.Cu" "F.Mask" "F.Paste")
			(net "P12V_E1S_EN_0_R")
		)
		(pad "2" smd circle
			(at 0.40005 0 180)
			(size 0 0)
			(layers "F.Cu" "F.Mask" "F.Paste")
			(net "GND")
		)
	)
	(footprint ""
		(layer "F.Cu")
		(at 42.637964 -172.922946 180)
		(property "Reference" "R5018"
			(at 0 0 180)
			(layer "F.SilkS")
			(hide yes)
			(effects
				(font
					(size 1.27 1.27)
				)
			)
		)
		(property "Value" ""
			(at 0 0 180)
			(layer "F.Fab")
			(effects
				(font
					(size 1.27 1.27)
				)
			)
		)
		(duplicate_pad_numbers_are_jumpers no)
		(fp_line
			(start 0.7874 0.4064)
			(end -0.7874 0.4064)
			(stroke
				(width 0.1524)
				(type default)
			)
			(layer "F.SilkS")
		)
		(fp_line
			(start 0.7874 -0.4064)
			(end 0.7874 0.4064)
			(stroke
				(width 0.1524)
				(type default)
			)
			(layer "F.SilkS")
		)
		(fp_line
			(start -0.7874 0.4064)
			(end -0.7874 -0.4064)
			(stroke
				(width 0.1524)
				(type default)
			)
			(layer "F.SilkS")
		)
		(fp_line
			(start -0.7874 -0.4064)
			(end 0.7874 -0.4064)
			(stroke
				(width 0.1524)
				(type default)
			)
			(layer "F.SilkS")
		)
		(fp_line
			(start 0.67945 0.3048)
			(end 0.120396 0.3048)
			(stroke
				(width 0.1)
				(type default)
			)
			(layer "F.Fab")
		)
		(fp_line
			(start 0.67945 -0.3048)
			(end 0.67945 0.3048)
			(stroke
				(width 0.1)
				(type default)
			)
			(layer "F.Fab")
		)
		(fp_line
			(start 0.12065 -0.2794)
			(end 0.12065 -0.3048)
			(stroke
				(width 0.1)
				(type default)
			)
			(layer "F.Fab")
		)
		(fp_line
			(start 0.12065 -0.3048)
			(end 0.67945 -0.3048)
			(stroke
				(width 0.1)
				(type default)
			)
			(layer "F.Fab")
		)
		(fp_line
			(start 0.120396 0.3048)
			(end 0.120396 0.2794)
			(stroke
				(width 0.1)
				(type default)
			)
			(layer "F.Fab")
		)
		(fp_line
			(start 0.120396 0.2794)
			(end -0.12065 0.2794)
			(stroke
				(width 0.1)
				(type default)
			)
			(layer "F.Fab")
		)
		(fp_line
			(start -0.12065 0.3048)
			(end -0.67945 0.3048)
			(stroke
				(width 0.1)
				(type default)
			)
			(layer "F.Fab")
		)
		(fp_line
			(start -0.12065 0.2794)
			(end -0.12065 0.3048)
			(stroke
				(width 0.1)
				(type default)
			)
			(layer "F.Fab")
		)
		(fp_line
			(start -0.12065 -0.2794)
			(end 0.12065 -0.2794)
			(stroke
				(width 0.1)
				(type default)
			)
			(layer "F.Fab")
		)
		(fp_line
			(start -0.12065 -0.305054)
			(end -0.12065 -0.2794)
			(stroke
				(width 0.1)
				(type default)
			)
			(layer "F.Fab")
		)
		(fp_line
			(start -0.67945 0.3048)
			(end -0.67945 -0.305054)
			(stroke
				(width 0.1)
				(type default)
			)
			(layer "F.Fab")
		)
		(fp_line
			(start -0.67945 -0.305054)
			(end -0.12065 -0.305054)
			(stroke
				(width 0.1)
				(type default)
			)
			(layer "F.Fab")
		)
		(pad "1" smd circle
			(at -0.40005 0 180)
			(size 0 0)
			(layers "F.Cu" "F.Mask" "F.Paste")
			(net "PVDD11_S3_P1")
		)
		(pad "2" smd circle
			(at 0.40005 0 180)
			(size 0 0)
			(layers "F.Cu" "F.Mask" "F.Paste")
			(net "I3C_SCM_2_R_SCL")
		)
	)
)
